# BASEBOARD_FAB2 (Tioga Pass) — schematic netlist excerpt (pin names and nets, part order shuffled) for the footprints in the layout excerpt that follows; sources: Cadence DE-HDL packaged netlist, KiCad conversion of Wiwynn_Tioga_Pass_MB.brd

R2T46  RES  22.1 1.0% CHIP  pkg 0402  page 101 : A = CLK_50M_CKMNG_BMC_1_R ; B = CLK_50M_CKMNG_BMC_1
RT4  1R3F-GP  1%  pkg RCL_GP  page 202 : \1\ = VR_PVCCIN_CPU0_PHASE2_RC ; \2\ = GND
R1W21  RES  0.0 5% CHIP  pkg 0402  page 199 : A = GND ; B = TEMP_SENSOR_E

(kicad_pcb
	(version 20260206)
	(generator "pcbnew")
	(generator_version "10.0")
	(general
		(thickness 1.6)
		(legacy_teardrops no)
	)
	(paper "A4")
	(title_block
		(title "Wiwynn_Tioga_Pass_MB.brd")
		(comment 1 "Tioga Pass / footprints 1631-1633 of 4770")
	)
	(layers
		(0 "F.Cu" signal "TOP")
		(4 "In1.Cu" signal "L2GND")
		(6 "In2.Cu" signal "L3")
		(8 "In3.Cu" signal "L4GND")
		(10 "In4.Cu" signal "L5")
		(12 "In5.Cu" signal "L6GND")
		(14 "In6.Cu" signal "L7VCC")
		(16 "In7.Cu" signal "L8VCC")
		(18 "In8.Cu" signal "L9GND")
		(20 "In9.Cu" signal "L10")
		(22 "In10.Cu" signal "L11GND")
		(24 "In11.Cu" signal "L12")
		(26 "In12.Cu" signal "L13GND")
		(2 "B.Cu" signal "BOTTOM")
		(9 "F.Adhes" user "F.Adhesive")
		(11 "B.Adhes" user "B.Adhesive")
		(13 "F.Paste" user "Package Geometry/Pastemask Top")
		(15 "B.Paste" user "Package Geometry/Pastemask Bottom")
		(5 "F.SilkS" user "Ref Des/Silkscreen Top")
		(7 "B.SilkS" user "Ref Des/Silkscreen Bottom")
		(1 "F.Mask" user "Board Geometry/Soldermask Top")
		(3 "B.Mask" user "Board Geometry/Soldermask Bottom")
		(17 "Dwgs.User" user "User.Drawings")
		(19 "Cmts.User" user "User.Comments")
		(21 "Eco1.User" user "User.Eco1")
		(23 "Eco2.User" user "User.Eco2")
		(25 "Edge.Cuts" user "Board Geometry/Outline")
		(27 "Margin" user)
		(31 "F.CrtYd" user "Package Geometry/Place Bound Top")
		(29 "B.CrtYd" user "Package Geometry/Place Bound Bottom")
		(35 "F.Fab" user "Ref Des/Assembly Top")
		(33 "B.Fab" user "Ref Des/Assembly Bottom")
	)
	(footprint ""
		(layer "F.Cu")
		(at 202.273154 -61.205364 -90)
		(property "Reference" "RT4"
			(at 0 0 270)
			(layer "F.SilkS")
			(hide yes)
			(effects
				(font
					(size 1.27 1.27)
				)
			)
		)
		(property "Value" "*"
			(at -0.0254 -2.6289 270)
			(unlocked yes)
			(layer "F.Fab")
			(hide yes)
			(effects
				(font
					(size 1.27 1.016)
					(thickness 0.1524)
				)
			)
		)
		(property "Device Type" "1R3F-GP_RCL_GP-1R3F-GP,64.1R00A"
			(at -0.0254 -4.1529 270)
			(unlocked yes)
			(layer "F.Fab")
			(hide yes)
			(effects
				(font
					(size 1.27 1.016)
					(thickness 0.1524)
				)
			)
		)
		(duplicate_pad_numbers_are_jumpers no)
		(fp_line
			(start -0.4826 0)
			(end -0.2032 0)
			(stroke
				(width 0.2032)
				(type default)
			)
			(layer "F.SilkS")
		)
		(fp_line
			(start 0.2032 0)
			(end 0.4826 0)
			(stroke
				(width 0.2032)
				(type default)
			)
			(layer "F.SilkS")
		)
		(fp_rect
			(start -0.5842 1.3335)
			(end 0.5842 -1.3335)
			(stroke
				(width 0)
				(type default)
			)
			(fill no)
			(layer "F.CrtYd")
		)
		(fp_rect
			(start -0.5842 1.3335)
			(end 0.5842 -1.3335)
			(stroke
				(width 0)
				(type default)
			)
			(fill no)
			(layer "F.Fab")
		)
		(pad "1" smd custom
			(at 0 -0.762 270)
			(size 0.2159 0.2159)
			(layers "F.Cu" "F.Mask" "F.Paste")
			(net "VR_PVCCIN_CPU0_PHASE2_RC")
			(options
				(clearance outline)
				(anchor circle)
			)
			(primitives
				(gr_poly
					(pts
						(arc
							(start -0.3302 -0.4318)
							(mid -0.402042 -0.402042)
							(end -0.4318 -0.3302)
						)
						(arc
							(start -0.4318 0.3302)
							(mid -0.402042 0.402042)
							(end -0.3302 0.4318)
						)
						(arc
							(start 0.3302 0.4318)
							(mid 0.402042 0.402042)
							(end 0.4318 0.3302)
						)
						(arc
							(start 0.4318 -0.3302)
							(mid 0.402042 -0.402042)
							(end 0.3302 -0.4318)
						)
					)
					(width 0)
					(fill yes)
				)
			)
		)
		(pad "2" smd custom
			(at 0 0.762 270)
			(size 0.2159 0.2159)
			(layers "F.Cu" "F.Mask" "F.Paste")
			(net "GND")
			(options
				(clearance outline)
				(anchor circle)
			)
			(primitives
				(gr_poly
					(pts
						(arc
							(start -0.3302 -0.4318)
							(mid -0.402042 -0.402042)
							(end -0.4318 -0.3302)
						)
						(arc
							(start -0.4318 0.3302)
							(mid -0.402042 0.402042)
							(end -0.3302 0.4318)
						)
						(arc
							(start 0.3302 0.4318)
							(mid 0.402042 0.402042)
							(end 0.4318 0.3302)
						)
						(arc
							(start 0.4318 -0.3302)
							(mid 0.402042 -0.402042)
							(end 0.3302 -0.4318)
						)
					)
					(width 0)
					(fill yes)
				)
			)
		)
	)
	(footprint ""
		(layer "F.Cu")
		(at 23.0505 -67.848988 90)
		(property "Reference" "R1W21"
			(at -0.8382 -0.67818 90)
			(unlocked yes)
			(layer "F.SilkS")
			(effects
				(font
					(size 0.4064 0.254)
					(thickness 0.1524)
				)
				(justify left)
			)
		)
		(property "Value" ""
			(at 0 0 90)
			(layer "F.Fab")
			(effects
				(font
					(size 1.27 1.27)
				)
			)
		)
		(duplicate_pad_numbers_are_jumpers no)
		(fp_poly
			(pts
				(xy -0.2794 -0.1016) (xy 0.2794 -0.1016) (xy 0.2794 0.9906) (xy -0.2794 0.9906)
			)
			(stroke
				(width 0)
				(type default)
			)
			(fill no)
			(layer "F.CrtYd")
		)
		(fp_line
			(start 0.2794 -0.1016)
			(end -0.2794 -0.1016)
			(stroke
				(width 0.1)
				(type default)
			)
			(layer "F.Fab")
		)
		(fp_line
			(start -0.2794 -0.1016)
			(end -0.2794 0.9906)
			(stroke
				(width 0.1)
				(type default)
			)
			(layer "F.Fab")
		)
		(fp_line
			(start 0.2794 0.9906)
			(end 0.2794 -0.1016)
			(stroke
				(width 0.1)
				(type default)
			)
			(layer "F.Fab")
		)
		(fp_line
			(start -0.2794 0.9906)
			(end 0.2794 0.9906)
			(stroke
				(width 0.1)
				(type default)
			)
			(layer "F.Fab")
		)
		(pad "1" smd rect
			(at 0 0 90)
			(size 0.508 0.508)
			(layers "F.Cu" "F.Mask" "F.Paste")
			(net "GND")
		)
		(pad "2" smd rect
			(at 0 0.889 90)
			(size 0.508 0.508)
			(layers "F.Cu" "F.Mask" "F.Paste")
			(net "TEMP_SENSOR_E")
		)
		(zone
			(layer "F.Cu")
			(hatch none 0.5)
			(connect_pads
				(clearance 0)
			)
			(min_thickness 0.25)
			(keepout
				(tracks allowed)
				(vias not_allowed)
				(pads allowed)
				(copperpour not_allowed)
				(footprints allowed)
			)
			(placement
				(enabled no)
				(sheetname "")
			)
			(fill
				(thermal_gap 0.5)
				(thermal_bridge_width 0.5)
				(island_removal_mode 0)
			)
			(polygon
				(pts
					(xy 23.3045 -67.594988) (xy 23.3045 -68.102988) (xy 23.6855 -68.102988) (xy 23.6855 -67.594988)
				)
			)
		)
		(zone
			(layer "F.Cu")
			(hatch none 0.5)
			(connect_pads
				(clearance 0)
			)
			(min_thickness 0.25)
			(keepout
				(tracks not_allowed)
				(vias allowed)
				(pads allowed)
				(copperpour not_allowed)
				(footprints allowed)
			)
			(placement
				(enabled no)
				(sheetname "")
			)
			(fill
				(thermal_gap 0.5)
				(thermal_bridge_width 0.5)
				(island_removal_mode 0)
			)
			(polygon
				(pts
					(xy 23.6855 -67.594988) (xy 23.6855 -68.102988) (xy 23.3045 -68.102988) (xy 23.3045 -67.594988)
				)
			)
		)
	)
	(footprint ""
		(layer "F.Cu")
		(at 474.98 -35.7505 180)
		(property "Reference" "R2T46"
			(at 0 0 180)
			(layer "F.SilkS")
			(hide yes)
			(effects
				(font
					(size 1.27 1.27)
				)
			)
		)
		(property "Value" ""
			(at 0 0 180)
			(layer "F.Fab")
			(effects
				(font
					(size 1.27 1.27)
				)
			)
		)
		(duplicate_pad_numbers_are_jumpers no)
		(fp_poly
			(pts
				(xy -0.2794 -0.1016) (xy 0.2794 -0.1016) (xy 0.2794 0.9906) (xy -0.2794 0.9906)
			)
			(stroke
				(width 0)
				(type default)
			)
			(fill no)
			(layer "F.CrtYd")
		)
		(fp_line
			(start 0.2794 0.9906)
			(end 0.2794 -0.1016)
			(stroke
				(width 0.1)
				(type default)
			)
			(layer "F.Fab")
		)
		(fp_line
			(start 0.2794 -0.1016)
			(end -0.2794 -0.1016)
			(stroke
				(width 0.1)
				(type default)
			)
			(layer "F.Fab")
		)
		(fp_line
			(start -0.2794 0.9906)
			(end 0.2794 0.9906)
			(stroke
				(width 0.1)
				(type default)
			)
			(layer "F.Fab")
		)
		(fp_line
			(start -0.2794 -0.1016)
			(end -0.2794 0.9906)
			(stroke
				(width 0.1)
				(type default)
			)
			(layer "F.Fab")
		)
		(pad "1" smd rect
			(at 0 0 180)
			(size 0.508 0.508)
			(layers "F.Cu" "F.Mask" "F.Paste")
			(net "CLK_50M_CKMNG_BMC_1_R")
		)
		(pad "2" smd rect
			(at 0 0.889 180)
			(size 0.508 0.508)
			(layers "F.Cu" "F.Mask" "F.Paste")
			(net "CLK_50M_CKMNG_BMC_1")
		)
		(zone
			(layer "F.Cu")
			(hatch none 0.5)
			(connect_pads
				(clearance 0)
			)
			(min_thickness 0.25)
			(keepout
				(tracks not_allowed)
				(vias allowed)
				(pads allowed)
				(copperpour not_allowed)
				(footprints allowed)
			)
			(placement
				(enabled no)
				(sheetname "")
			)
			(fill
				(thermal_gap 0.5)
				(thermal_bridge_width 0.5)
				(island_removal_mode 0)
			)
			(polygon
				(pts
					(xy 475.234 -36.3855) (xy 474.726 -36.3855) (xy 474.726 -36.0045) (xy 475.234 -36.0045)
				)
			)
		)
		(zone
			(layer "F.Cu")
			(hatch none 0.5)
			(connect_pads
				(clearance 0)
			)
			(min_thickness 0.25)
			(keepout
				(tracks allowed)
				(vias not_allowed)
				(pads allowed)
				(copperpour not_allowed)
				(footprints allowed)
			)
			(placement
				(enabled no)
				(sheetname "")
			)
			(fill
				(thermal_gap 0.5)
				(thermal_bridge_width 0.5)
				(island_removal_mode 0)
			)
			(polygon
				(pts
					(xy 475.234 -36.0045) (xy 474.726 -36.0045) (xy 474.726 -36.3855) (xy 475.234 -36.3855)
				)
			)
		)
	)
)
